(kicad_pcb
	(version 20260206)
	(generator "pcbnew")
	(generator_version "10.0")
	(general
		(thickness 1.6)
		(legacy_teardrops no)
	)
	(paper "A4")
	(title_block
		(title "Wiwynn_Tioga_Pass_MB.brd")
		(comment 1 "Tioga Pass / footprints 2830-2837 of 4770")
	)
	(layers
		(0 "F.Cu" signal "TOP")
		(4 "In1.Cu" signal "L2GND")
		(6 "In2.Cu" signal "L3")
		(8 "In3.Cu" signal "L4GND")
		(10 "In4.Cu" signal "L5")
		(12 "In5.Cu" signal "L6GND")
		(14 "In6.Cu" signal "L7VCC")
		(16 "In7.Cu" signal "L8VCC")
		(18 "In8.Cu" signal "L9GND")
		(20 "In9.Cu" signal "L10")
		(22 "In10.Cu" signal "L11GND")
		(24 "In11.Cu" signal "L12")
		(26 "In12.Cu" signal "L13GND")
		(2 "B.Cu" signal "BOTTOM")
		(9 "F.Adhes" user "F.Adhesive")
		(11 "B.Adhes" user "B.Adhesive")
		(13 "F.Paste" user "Package Geometry/Pastemask Top")
		(15 "B.Paste" user "Package Geometry/Pastemask Bottom")
		(5 "F.SilkS" user "Ref Des/Silkscreen Top")
		(7 "B.SilkS" user "Ref Des/Silkscreen Bottom")
		(1 "F.Mask" user "Board Geometry/Soldermask Top")
		(3 "B.Mask" user "Board Geometry/Soldermask Bottom")
		(17 "Dwgs.User" user "User.Drawings")
		(19 "Cmts.User" user "User.Comments")
		(21 "Eco1.User" user "User.Eco1")
		(23 "Eco2.User" user "User.Eco2")
		(25 "Edge.Cuts" user "Board Geometry/Outline")
		(27 "Margin" user)
		(31 "F.CrtYd" user "Package Geometry/Place Bound Top")
		(29 "B.CrtYd" user "Package Geometry/Place Bound Bottom")
		(35 "F.Fab" user "Ref Des/Assembly Top")
		(33 "B.Fab" user "Ref Des/Assembly Bottom")
	)
	(footprint ""
		(layer "B.Cu")
		(at 342.0872 -88.3412 -90)
		(property "Reference" "R3P1"
			(at 0 0 90)
			(layer "B.SilkS")
			(hide yes)
			(effects
				(font
					(size 1.27 1.27)
				)
				(justify mirror)
			)
		)
		(property "Value" ""
			(at 0 0 90)
			(layer "B.Fab")
			(effects
				(font
					(size 1.27 1.27)
				)
				(justify mirror)
			)
		)
		(duplicate_pad_numbers_are_jumpers no)
		(fp_poly
			(pts
				(xy 0.2794 -0.1016) (xy -0.2794 -0.1016) (xy -0.2794 0.9906) (xy 0.2794 0.9906)
			)
			(stroke
				(width 0)
				(type default)
			)
			(fill no)
			(layer "B.CrtYd")
		)
		(fp_line
			(start -0.2794 0.9906)
			(end -0.2794 -0.1016)
			(stroke
				(width 0.1)
				(type default)
			)
			(layer "B.Fab")
		)
		(fp_line
			(start 0.2794 0.9906)
			(end -0.2794 0.9906)
			(stroke
				(width 0.1)
				(type default)
			)
			(layer "B.Fab")
		)
		(fp_line
			(start -0.2794 -0.1016)
			(end 0.2794 -0.1016)
			(stroke
				(width 0.1)
				(type default)
			)
			(layer "B.Fab")
		)
		(fp_line
			(start 0.2794 -0.1016)
			(end 0.2794 0.9906)
			(stroke
				(width 0.1)
				(type default)
			)
			(layer "B.Fab")
		)
		(pad "1" smd rect
			(at 0 0 90)
			(size 0.508 0.508)
			(layers "B.Cu" "B.Mask" "B.Paste")
			(net "SVID_ALERT_PVCCIO_CPU0")
		)
		(pad "2" smd rect
			(at 0 0.889 90)
			(size 0.508 0.508)
			(layers "B.Cu" "B.Mask" "B.Paste")
			(net "SVID_ALERT0_CPU0_R_N")
		)
		(zone
			(layer "B.Cu")
			(hatch none 0.5)
			(connect_pads
				(clearance 0)
			)
			(min_thickness 0.25)
			(keepout
				(tracks not_allowed)
				(vias allowed)
				(pads allowed)
				(copperpour not_allowed)
				(footprints allowed)
			)
			(placement
				(enabled no)
				(sheetname "")
			)
			(fill
				(thermal_gap 0.5)
				(thermal_bridge_width 0.5)
				(island_removal_mode 0)
			)
			(polygon
				(pts
					(xy 341.4522 -88.0872) (xy 341.4522 -88.5952) (xy 341.8332 -88.5952) (xy 341.8332 -88.0872)
				)
			)
		)
		(zone
			(layer "B.Cu")
			(hatch none 0.5)
			(connect_pads
				(clearance 0)
			)
			(min_thickness 0.25)
			(keepout
				(tracks allowed)
				(vias not_allowed)
				(pads allowed)
				(copperpour not_allowed)
				(footprints allowed)
			)
			(placement
				(enabled no)
				(sheetname "")
			)
			(fill
				(thermal_gap 0.5)
				(thermal_bridge_width 0.5)
				(island_removal_mode 0)
			)
			(polygon
				(pts
					(xy 341.8332 -88.0872) (xy 341.8332 -88.5952) (xy 341.4522 -88.5952) (xy 341.4522 -88.0872)
				)
			)
		)
	)
	(footprint ""
		(layer "B.Cu")
		(at 477.645222 -3.3782 90)
		(property "Reference" "R9G9"
			(at 0 0 90)
			(layer "B.SilkS")
			(hide yes)
			(effects
				(font
					(size 1.27 1.27)
				)
				(justify mirror)
			)
		)
		(property "Value" ""
			(at 0 0 90)
			(layer "B.Fab")
			(effects
				(font
					(size 1.27 1.27)
				)
				(justify mirror)
			)
		)
		(duplicate_pad_numbers_are_jumpers no)
		(fp_poly
			(pts
				(xy 0.2794 -0.1016) (xy -0.2794 -0.1016) (xy -0.2794 0.9906) (xy 0.2794 0.9906)
			)
			(stroke
				(width 0)
				(type default)
			)
			(fill no)
			(layer "B.CrtYd")
		)
		(fp_line
			(start 0.2794 -0.1016)
			(end 0.2794 0.9906)
			(stroke
				(width 0.1)
				(type default)
			)
			(layer "B.Fab")
		)
		(fp_line
			(start -0.2794 -0.1016)
			(end 0.2794 -0.1016)
			(stroke
				(width 0.1)
				(type default)
			)
			(layer "B.Fab")
		)
		(fp_line
			(start 0.2794 0.9906)
			(end -0.2794 0.9906)
			(stroke
				(width 0.1)
				(type default)
			)
			(layer "B.Fab")
		)
		(fp_line
			(start -0.2794 0.9906)
			(end -0.2794 -0.1016)
			(stroke
				(width 0.1)
				(type default)
			)
			(layer "B.Fab")
		)
		(pad "1" smd rect
			(at 0 0 270)
			(size 0.508 0.508)
			(layers "B.Cu" "B.Mask" "B.Paste")
			(net "NIC_SER_P_MDI_3_DP")
		)
		(pad "2" smd rect
			(at 0 0.889 270)
			(size 0.508 0.508)
			(layers "B.Cu" "B.Mask" "B.Paste")
			(net "NIC_MDI_SPRV_RJ45_3_R_DP")
		)
		(zone
			(layer "B.Cu")
			(hatch none 0.5)
			(connect_pads
				(clearance 0)
			)
			(min_thickness 0.25)
			(keepout
				(tracks allowed)
				(vias not_allowed)
				(pads allowed)
				(copperpour not_allowed)
				(footprints allowed)
			)
			(placement
				(enabled no)
				(sheetname "")
			)
			(fill
				(thermal_gap 0.5)
				(thermal_bridge_width 0.5)
				(island_removal_mode 0)
			)
			(polygon
				(pts
					(xy 477.899222 -3.6322) (xy 477.899222 -3.1242) (xy 478.280222 -3.1242) (xy 478.280222 -3.6322)
				)
			)
		)
		(zone
			(layer "B.Cu")
			(hatch none 0.5)
			(connect_pads
				(clearance 0)
			)
			(min_thickness 0.25)
			(keepout
				(tracks not_allowed)
				(vias allowed)
				(pads allowed)
				(copperpour not_allowed)
				(footprints allowed)
			)
			(placement
				(enabled no)
				(sheetname "")
			)
			(fill
				(thermal_gap 0.5)
				(thermal_bridge_width 0.5)
				(island_removal_mode 0)
			)
			(polygon
				(pts
					(xy 478.280222 -3.6322) (xy 478.280222 -3.1242) (xy 477.899222 -3.1242) (xy 477.899222 -3.6322)
				)
			)
		)
	)
	(footprint ""
		(layer "B.Cu")
		(at 176.7078 -79.502 -90)
		(property "Reference" "FB6P1"
			(at 0.53467 4.4958 0)
			(unlocked yes)
			(layer "B.SilkS")
			(effects
				(font
					(size 0.7874 0.5842)
					(thickness 0.1524)
				)
				(justify mirror)
			)
		)
		(property "Value" ""
			(at 0 0 90)
			(layer "B.Fab")
			(effects
				(font
					(size 1.27 1.27)
				)
				(justify mirror)
			)
		)
		(duplicate_pad_numbers_are_jumpers no)
		(fp_poly
			(pts
				(xy 0.7239 -0.26035) (xy -0.7239 -0.26035) (xy -0.7239 2.03835) (xy 0.7239 2.03835)
			)
			(stroke
				(width 0)
				(type default)
			)
			(fill no)
			(layer "B.CrtYd")
		)
		(fp_line
			(start -0.7239 2.03835)
			(end 0.7239 2.03835)
			(stroke
				(width 0.1)
				(type default)
			)
			(layer "B.Fab")
		)
		(fp_line
			(start 0.7239 2.03835)
			(end 0.7239 -0.26035)
			(stroke
				(width 0.1)
				(type default)
			)
			(layer "B.Fab")
		)
		(fp_line
			(start -0.7239 -0.26035)
			(end -0.7239 2.03835)
			(stroke
				(width 0.1)
				(type default)
			)
			(layer "B.Fab")
		)
		(fp_line
			(start 0.7239 -0.26035)
			(end -0.7239 -0.26035)
			(stroke
				(width 0.1)
				(type default)
			)
			(layer "B.Fab")
		)
		(pad "1" smd rect
			(at 0 0 90)
			(size 1.27 1.016)
			(layers "B.Cu" "B.Mask" "B.Paste")
			(net "P3V3")
		)
		(pad "2" smd rect
			(at 0 1.778 90)
			(size 1.27 1.016)
			(layers "B.Cu" "B.Mask" "B.Paste")
			(net "P3V3_DB1200")
		)
		(zone
			(layer "B.Cu")
			(hatch none 0.5)
			(connect_pads
				(clearance 0)
			)
			(min_thickness 0.25)
			(keepout
				(tracks not_allowed)
				(vias allowed)
				(pads allowed)
				(copperpour not_allowed)
				(footprints allowed)
			)
			(placement
				(enabled no)
				(sheetname "")
			)
			(fill
				(thermal_gap 0.5)
				(thermal_bridge_width 0.5)
				(island_removal_mode 0)
			)
			(polygon
				(pts
					(xy 176.1998 -80.137) (xy 175.4378 -80.137) (xy 175.4378 -80.0481) (xy 175.4378 -78.867) (xy 176.1998 -78.867)
				)
			)
		)
	)
	(footprint ""
		(layer "B.Cu")
		(at 390.144 -17.272 -90)
		(property "Reference" "C32W4"
			(at 0.8382 -0.67818 270)
			(unlocked yes)
			(layer "B.SilkS")
			(effects
				(font
					(size 0.4064 0.254)
					(thickness 0.1524)
				)
				(justify left mirror)
			)
		)
		(property "Value" ""
			(at 0 0 90)
			(layer "B.Fab")
			(effects
				(font
					(size 1.27 1.27)
				)
				(justify mirror)
			)
		)
		(duplicate_pad_numbers_are_jumpers no)
		(fp_poly
			(pts
				(xy -0.3048 -0.1016) (xy -0.3048 0.9906) (xy 0.3048 0.9906) (xy 0.3048 -0.1016)
			)
			(stroke
				(width 0)
				(type default)
			)
			(fill no)
			(layer "B.CrtYd")
		)
		(fp_line
			(start -0.3048 0.9906)
			(end -0.3048 -0.1016)
			(stroke
				(width 0.1)
				(type default)
			)
			(layer "B.Fab")
		)
		(fp_line
			(start 0.3048 0.9906)
			(end -0.3048 0.9906)
			(stroke
				(width 0.1)
				(type default)
			)
			(layer "B.Fab")
		)
		(fp_line
			(start -0.3048 -0.1016)
			(end 0.3048 -0.1016)
			(stroke
				(width 0.1)
				(type default)
			)
			(layer "B.Fab")
		)
		(fp_line
			(start 0.3048 -0.1016)
			(end 0.3048 0.9906)
			(stroke
				(width 0.1)
				(type default)
			)
			(layer "B.Fab")
		)
		(pad "1" smd rect
			(at 0 0 90)
			(size 0.508 0.508)
			(layers "B.Cu" "B.Mask" "B.Paste")
			(net "P3V3_STBY")
		)
		(pad "2" smd rect
			(at 0 0.889 90)
			(size 0.508 0.508)
			(layers "B.Cu" "B.Mask" "B.Paste")
			(net "GND")
		)
		(zone
			(layer "B.Cu")
			(hatch none 0.5)
			(connect_pads
				(clearance 0)
			)
			(min_thickness 0.25)
			(keepout
				(tracks not_allowed)
				(vias allowed)
				(pads allowed)
				(copperpour not_allowed)
				(footprints allowed)
			)
			(placement
				(enabled no)
				(sheetname "")
			)
			(fill
				(thermal_gap 0.5)
				(thermal_bridge_width 0.5)
				(island_removal_mode 0)
			)
			(polygon
				(pts
					(xy 389.509 -17.018) (xy 389.509 -17.526) (xy 389.89 -17.526) (xy 389.89 -17.018)
				)
			)
		)
		(zone
			(layer "B.Cu")
			(hatch none 0.5)
			(connect_pads
				(clearance 0)
			)
			(min_thickness 0.25)
			(keepout
				(tracks allowed)
				(vias not_allowed)
				(pads allowed)
				(copperpour not_allowed)
				(footprints allowed)
			)
			(placement
				(enabled no)
				(sheetname "")
			)
			(fill
				(thermal_gap 0.5)
				(thermal_bridge_width 0.5)
				(island_removal_mode 0)
			)
			(polygon
				(pts
					(xy 389.89 -17.018) (xy 389.89 -17.526) (xy 389.509 -17.526) (xy 389.509 -17.018)
				)
			)
		)
	)
	(footprint ""
		(layer "B.Cu")
		(at 104.521254 -73.51014)
		(property "Reference" "C8P23"
			(at 0 0 0)
			(layer "B.SilkS")
			(hide yes)
			(effects
				(font
					(size 1.27 1.27)
				)
				(justify mirror)
			)
		)
		(property "Value" ""
			(at 0 0 0)
			(layer "B.Fab")
			(effects
				(font
					(size 1.27 1.27)
				)
				(justify mirror)
			)
		)
		(duplicate_pad_numbers_are_jumpers no)
		(fp_poly
			(pts
				(xy 0.7239 -0.2159) (xy -0.7239 -0.2159) (xy -0.7239 1.9939) (xy 0.7239 1.9939)
			)
			(stroke
				(width 0)
				(type default)
			)
			(fill no)
			(layer "B.CrtYd")
		)
		(fp_line
			(start -0.7239 -0.2159)
			(end 0.7239 -0.2159)
			(stroke
				(width 0.1)
				(type default)
			)
			(layer "B.Fab")
		)
		(fp_line
			(start -0.7239 1.9939)
			(end -0.7239 -0.2159)
			(stroke
				(width 0.1)
				(type default)
			)
			(layer "B.Fab")
		)
		(fp_line
			(start 0.7239 -0.2159)
			(end 0.7239 1.9939)
			(stroke
				(width 0.1)
				(type default)
			)
			(layer "B.Fab")
		)
		(fp_line
			(start 0.7239 1.9939)
			(end -0.7239 1.9939)
			(stroke
				(width 0.1)
				(type default)
			)
			(layer "B.Fab")
		)
		(pad "1" smd rect
			(at 0 0 180)
			(size 1.27 1.016)
			(layers "B.Cu" "B.Mask" "B.Paste")
			(net "PVCCMCP_CPU1")
		)
		(pad "2" smd rect
			(at 0 1.778 180)
			(size 1.27 1.016)
			(layers "B.Cu" "B.Mask" "B.Paste")
			(net "GND")
		)
		(zone
			(layer "B.Cu")
			(hatch none 0.5)
			(connect_pads
				(clearance 0)
			)
			(min_thickness 0.25)
			(keepout
				(tracks not_allowed)
				(vias allowed)
				(pads allowed)
				(copperpour not_allowed)
				(footprints allowed)
			)
			(placement
				(enabled no)
				(sheetname "")
			)
			(fill
				(thermal_gap 0.5)
				(thermal_bridge_width 0.5)
				(island_removal_mode 0)
			)
			(polygon
				(pts
					(xy 105.156254 -73.00214) (xy 103.886254 -73.00214) (xy 103.886254 -72.24014) (xy 105.156254 -72.24014)
				)
			)
		)
	)
	(footprint ""
		(layer "B.Cu")
		(at 178.562 -53.213 -90)
		(property "Reference" "C6R10"
			(at 0 0 90)
			(layer "B.SilkS")
			(hide yes)
			(effects
				(font
					(size 1.27 1.27)
				)
				(justify mirror)
			)
		)
		(property "Value" ""
			(at 0 0 90)
			(layer "B.Fab")
			(effects
				(font
					(size 1.27 1.27)
				)
				(justify mirror)
			)
		)
		(duplicate_pad_numbers_are_jumpers no)
		(fp_poly
			(pts
				(xy 0.7239 -0.2159) (xy -0.7239 -0.2159) (xy -0.7239 1.9939) (xy 0.7239 1.9939)
			)
			(stroke
				(width 0)
				(type default)
			)
			(fill no)
			(layer "B.CrtYd")
		)
		(fp_line
			(start -0.7239 1.9939)
			(end -0.7239 -0.2159)
			(stroke
				(width 0.1)
				(type default)
			)
			(layer "B.Fab")
		)
		(fp_line
			(start 0.7239 1.9939)
			(end -0.7239 1.9939)
			(stroke
				(width 0.1)
				(type default)
			)
			(layer "B.Fab")
		)
		(fp_line
			(start -0.7239 -0.2159)
			(end 0.7239 -0.2159)
			(stroke
				(width 0.1)
				(type default)
			)
			(layer "B.Fab")
		)
		(fp_line
			(start 0.7239 -0.2159)
			(end 0.7239 1.9939)
			(stroke
				(width 0.1)
				(type default)
			)
			(layer "B.Fab")
		)
		(pad "1" smd rect
			(at 0 0 90)
			(size 1.27 1.016)
			(layers "B.Cu" "B.Mask" "B.Paste")
			(net "VR_FET_SW_P12V_STBY_PVCCIN_CPU0")
		)
		(pad "2" smd rect
			(at 0 1.778 90)
			(size 1.27 1.016)
			(layers "B.Cu" "B.Mask" "B.Paste")
			(net "GND")
		)
		(zone
			(layer "B.Cu")
			(hatch none 0.5)
			(connect_pads
				(clearance 0)
			)
			(min_thickness 0.25)
			(keepout
				(tracks not_allowed)
				(vias allowed)
				(pads allowed)
				(copperpour not_allowed)
				(footprints allowed)
			)
			(placement
				(enabled no)
				(sheetname "")
			)
			(fill
				(thermal_gap 0.5)
				(thermal_bridge_width 0.5)
				(island_removal_mode 0)
			)
			(polygon
				(pts
					(xy 178.054 -52.578) (xy 178.054 -53.848) (xy 177.292 -53.848) (xy 177.292 -52.578)
				)
			)
		)
	)
	(footprint ""
		(layer "B.Cu")
		(at 197.239128 -87.043006 90)
		(property "Reference" "R6P47"
			(at 0 0 90)
			(layer "B.SilkS")
			(hide yes)
			(effects
				(font
					(size 1.27 1.27)
				)
				(justify mirror)
			)
		)
		(property "Value" ""
			(at 0 0 90)
			(layer "B.Fab")
			(effects
				(font
					(size 1.27 1.27)
				)
				(justify mirror)
			)
		)
		(duplicate_pad_numbers_are_jumpers no)
		(fp_rect
			(start 0.2794 -0.1016)
			(end -0.2794 0.9906)
			(stroke
				(width 0)
				(type default)
			)
			(fill no)
			(layer "B.CrtYd")
		)
		(fp_line
			(start 0.2794 -0.1016)
			(end 0.2794 0.9906)
			(stroke
				(width 0.1)
				(type default)
			)
			(layer "B.Fab")
		)
		(fp_line
			(start -0.2794 -0.1016)
			(end 0.2794 -0.1016)
			(stroke
				(width 0.1)
				(type default)
			)
			(layer "B.Fab")
		)
		(fp_line
			(start 0.2794 0.9906)
			(end -0.2794 0.9906)
			(stroke
				(width 0.1)
				(type default)
			)
			(layer "B.Fab")
		)
		(fp_line
			(start -0.2794 0.9906)
			(end -0.2794 -0.1016)
			(stroke
				(width 0.1)
				(type default)
			)
			(layer "B.Fab")
		)
		(pad "1" smd rect
			(at 0 0 270)
			(size 0.508 0.508)
			(layers "B.Cu" "B.Mask" "B.Paste")
			(net "VR_PVCCIN_CPU0_PH5_VCIN")
		)
		(pad "2" smd rect
			(at 0 0.889 270)
			(size 0.508 0.508)
			(layers "B.Cu" "B.Mask" "B.Paste")
			(net "P5V_STBY")
		)
		(zone
			(layer "B.Cu")
			(hatch none 0.5)
			(connect_pads
				(clearance 0)
			)
			(min_thickness 0.25)
			(keepout
				(tracks not_allowed)
				(vias allowed)
				(pads allowed)
				(copperpour not_allowed)
				(footprints allowed)
			)
			(placement
				(enabled no)
				(sheetname "")
			)
			(fill
				(thermal_gap 0.5)
				(thermal_bridge_width 0.5)
				(island_removal_mode 0)
			)
			(polygon
				(pts
					(xy 197.493128 -87.297006) (xy 197.493128 -86.789006) (xy 197.874128 -86.789006) (xy 197.874128 -87.297006)
				)
			)
		)
		(zone
			(layer "B.Cu")
			(hatch none 0.5)
			(connect_pads
				(clearance 0)
			)
			(min_thickness 0.25)
			(keepout
				(tracks allowed)
				(vias not_allowed)
				(pads allowed)
				(copperpour not_allowed)
				(footprints allowed)
			)
			(placement
				(enabled no)
				(sheetname "")
			)
			(fill
				(thermal_gap 0.5)
				(thermal_bridge_width 0.5)
				(island_removal_mode 0)
			)
			(polygon
				(pts
					(xy 197.493128 -87.297006) (xy 197.493128 -86.789006) (xy 197.874128 -86.789006) (xy 197.874128 -87.297006)
				)
			)
		)
	)
	(footprint ""
		(layer "B.Cu")
		(at 397.764 -85.0265 180)
		(property "Reference" "R8D17"
			(at 0.8382 -0.67818 180)
			(unlocked yes)
			(layer "B.SilkS")
			(effects
				(font
					(size 0.4064 0.254)
					(thickness 0.1524)
				)
				(justify left mirror)
			)
		)
		(property "Value" ""
			(at 0 0 0)
			(layer "B.Fab")
			(effects
				(font
					(size 1.27 1.27)
				)
				(justify mirror)
			)
		)
		(duplicate_pad_numbers_are_jumpers no)
		(fp_poly
			(pts
				(xy 0.2794 -0.1016) (xy -0.2794 -0.1016) (xy -0.2794 0.9906) (xy 0.2794 0.9906)
			)
			(stroke
				(width 0)
				(type default)
			)
			(fill no)
			(layer "B.CrtYd")
		)
		(fp_line
			(start 0.2794 0.9906)
			(end -0.2794 0.9906)
			(stroke
				(width 0.1)
				(type default)
			)
			(layer "B.Fab")
		)
		(fp_line
			(start 0.2794 -0.1016)
			(end 0.2794 0.9906)
			(stroke
				(width 0.1)
				(type default)
			)
			(layer "B.Fab")
		)
		(fp_line
			(start -0.2794 0.9906)
			(end -0.2794 -0.1016)
			(stroke
				(width 0.1)
				(type default)
			)
			(layer "B.Fab")
		)
		(fp_line
			(start -0.2794 -0.1016)
			(end 0.2794 -0.1016)
			(stroke
				(width 0.1)
				(type default)
			)
			(layer "B.Fab")
		)
		(pad "1" smd rect
			(at 0 0)
			(size 0.508 0.508)
			(layers "B.Cu" "B.Mask" "B.Paste")
			(net "P3V3_STBY")
		)
		(pad "2" smd rect
			(at 0 0.889)
			(size 0.508 0.508)
			(layers "B.Cu" "B.Mask" "B.Paste")
			(net "SMB_VR_STBY_LVC3_SDA")
		)
		(zone
			(layer "B.Cu")
			(hatch none 0.5)
			(connect_pads
				(clearance 0)
			)
			(min_thickness 0.25)
			(keepout
				(tracks not_allowed)
				(vias allowed)
				(pads allowed)
				(copperpour not_allowed)
				(footprints allowed)
			)
			(placement
				(enabled no)
				(sheetname "")
			)
			(fill
				(thermal_gap 0.5)
				(thermal_bridge_width 0.5)
				(island_removal_mode 0)
			)
			(polygon
				(pts
					(xy 397.51 -85.6615) (xy 398.018 -85.6615) (xy 398.018 -85.2805) (xy 397.51 -85.2805)
				)
			)
		)
		(zone
			(layer "B.Cu")
			(hatch none 0.5)
			(connect_pads
				(clearance 0)
			)
			(min_thickness 0.25)
			(keepout
				(tracks allowed)
				(vias not_allowed)
				(pads allowed)
				(copperpour not_allowed)
				(footprints allowed)
			)
			(placement
				(enabled no)
				(sheetname "")
			)
			(fill
				(thermal_gap 0.5)
				(thermal_bridge_width 0.5)
				(island_removal_mode 0)
			)
			(polygon
				(pts
					(xy 397.51 -85.2805) (xy 398.018 -85.2805) (xy 398.018 -85.6615) (xy 397.51 -85.6615)
				)
			)
		)
	)
)
